# T6G (Grand Teton) — schematic netlist excerpt (pin names and nets, part order shuffled) for the footprints in the layout excerpt that follows; sources: Cadence DE-HDL packaged netlist, KiCad conversion of 04192023_DAF0TMB3IC0_F0TG_MB_C_brd_V02_OCP.brd

R507  Q_RES  15 1% CHIP  pkg 0402LF  page 44 : A = M_H_CPU1_ALERT_N ; B = M_H_CPU1_ALERT_R_N
PR192  Q_RES  0 5% CHIP  pkg 0402LF  page 211 : A = PVDDCR_CPU0_P1_VOS2 ; B = PVDDCR_CPU0_P1
PC140_5  Q_CAP  22UF 4V 20% X6S  pkg C0805  page 203 : A = PVDDCR_CPU1_P0 ; B = GND

(kicad_pcb
	(version 20260206)
	(generator "pcbnew")
	(generator_version "10.0")
	(general
		(thickness 1.6)
		(legacy_teardrops no)
	)
	(paper "A4")
	(title_block
		(title "04192023_DAF0TMB3IC0_F0TG_MB_C_brd_V02_OCP.brd")
		(comment 1 "Grand Teton / footprints 6644-6646 of 8354")
	)
	(layers
		(0 "F.Cu" signal "TOP")
		(4 "In1.Cu" signal "GND")
		(6 "In2.Cu" signal "IN1")
		(8 "In3.Cu" signal "GND1")
		(10 "In4.Cu" signal "IN2")
		(12 "In5.Cu" signal "GND2")
		(14 "In6.Cu" signal "IN3")
		(16 "In7.Cu" signal "GND3")
		(18 "In8.Cu" signal "VCC")
		(20 "In9.Cu" signal "VCC1")
		(22 "In10.Cu" signal "GND4")
		(24 "In11.Cu" signal "IN4")
		(26 "In12.Cu" signal "GND5")
		(28 "In13.Cu" signal "IN5")
		(30 "In14.Cu" signal "GND6")
		(32 "In15.Cu" signal "IN6")
		(34 "In16.Cu" signal "GND7")
		(2 "B.Cu" signal "BOTTOM")
		(9 "F.Adhes" user "F.Adhesive")
		(11 "B.Adhes" user "B.Adhesive")
		(13 "F.Paste" user "Package Geometry/Pastemask Top")
		(15 "B.Paste" user "Package Geometry/Pastemask Bottom")
		(5 "F.SilkS" user "Ref Des/Silkscreen Top")
		(7 "B.SilkS" user "Ref Des/Silkscreen Bottom")
		(1 "F.Mask" user "Board Geometry/Soldermask Top")
		(3 "B.Mask" user "Board Geometry/Soldermask Bottom")
		(17 "Dwgs.User" user "User.Drawings")
		(19 "Cmts.User" user "User.Comments")
		(21 "Eco1.User" user "User.Eco1")
		(23 "Eco2.User" user "User.Eco2")
		(25 "Edge.Cuts" user "Board Geometry/Outline")
		(27 "Margin" user)
		(31 "F.CrtYd" user "Package Geometry/Place Bound Top")
		(29 "B.CrtYd" user "Package Geometry/Place Bound Bottom")
		(35 "F.Fab" user "Ref Des/Assembly Top")
		(33 "B.Fab" user "Ref Des/Assembly Bottom")
	)
	(footprint ""
		(layer "B.Cu")
		(at 94.34322 -180.010562 90)
		(property "Reference" "PR192"
			(at 0 0 90)
			(layer "B.SilkS")
			(hide yes)
			(effects
				(font
					(size 1.27 1.27)
				)
				(justify mirror)
			)
		)
		(property "Value" ""
			(at 0 0 90)
			(layer "B.Fab")
			(effects
				(font
					(size 1.27 1.27)
				)
				(justify mirror)
			)
		)
		(duplicate_pad_numbers_are_jumpers no)
		(fp_line
			(start 0.7874 -0.4064)
			(end -0.7874 -0.4064)
			(stroke
				(width 0.1524)
				(type default)
			)
			(layer "B.SilkS")
		)
		(fp_line
			(start -0.7874 -0.4064)
			(end -0.7874 0.4064)
			(stroke
				(width 0.1524)
				(type default)
			)
			(layer "B.SilkS")
		)
		(fp_line
			(start 0.7874 0.4064)
			(end 0.7874 -0.4064)
			(stroke
				(width 0.1524)
				(type default)
			)
			(layer "B.SilkS")
		)
		(fp_line
			(start -0.7874 0.4064)
			(end 0.7874 0.4064)
			(stroke
				(width 0.1524)
				(type default)
			)
			(layer "B.SilkS")
		)
		(fp_line
			(start 0.67945 -0.305054)
			(end 0.12065 -0.305054)
			(stroke
				(width 0.1)
				(type default)
			)
			(layer "B.Fab")
		)
		(fp_line
			(start 0.12065 -0.305054)
			(end 0.12065 -0.2794)
			(stroke
				(width 0.1)
				(type default)
			)
			(layer "B.Fab")
		)
		(fp_line
			(start -0.12065 -0.3048)
			(end -0.67945 -0.3048)
			(stroke
				(width 0.1)
				(type default)
			)
			(layer "B.Fab")
		)
		(fp_line
			(start -0.67945 -0.3048)
			(end -0.67945 0.3048)
			(stroke
				(width 0.1)
				(type default)
			)
			(layer "B.Fab")
		)
		(fp_line
			(start 0.12065 -0.2794)
			(end -0.12065 -0.2794)
			(stroke
				(width 0.1)
				(type default)
			)
			(layer "B.Fab")
		)
		(fp_line
			(start -0.12065 -0.2794)
			(end -0.12065 -0.3048)
			(stroke
				(width 0.1)
				(type default)
			)
			(layer "B.Fab")
		)
		(fp_line
			(start 0.12065 0.2794)
			(end 0.12065 0.3048)
			(stroke
				(width 0.1)
				(type default)
			)
			(layer "B.Fab")
		)
		(fp_line
			(start -0.120396 0.2794)
			(end 0.12065 0.2794)
			(stroke
				(width 0.1)
				(type default)
			)
			(layer "B.Fab")
		)
		(fp_line
			(start 0.67945 0.3048)
			(end 0.67945 -0.305054)
			(stroke
				(width 0.1)
				(type default)
			)
			(layer "B.Fab")
		)
		(fp_line
			(start 0.12065 0.3048)
			(end 0.67945 0.3048)
			(stroke
				(width 0.1)
				(type default)
			)
			(layer "B.Fab")
		)
		(fp_line
			(start -0.120396 0.3048)
			(end -0.120396 0.2794)
			(stroke
				(width 0.1)
				(type default)
			)
			(layer "B.Fab")
		)
		(fp_line
			(start -0.67945 0.3048)
			(end -0.120396 0.3048)
			(stroke
				(width 0.1)
				(type default)
			)
			(layer "B.Fab")
		)
		(pad "1" smd circle
			(at 0.40005 0 270)
			(size 0 0)
			(layers "B.Cu" "B.Mask" "B.Paste")
			(net "PVDDCR_CPU0_P1_VOS2")
		)
		(pad "2" smd circle
			(at -0.40005 0 270)
			(size 0 0)
			(layers "B.Cu" "B.Mask" "B.Paste")
			(net "PVDDCR_CPU0_P1")
		)
	)
	(footprint ""
		(layer "B.Cu")
		(at 339.93582 -326.363076 -90)
		(property "Reference" "PC140_5"
			(at 0 0 90)
			(layer "B.SilkS")
			(hide yes)
			(effects
				(font
					(size 1.27 1.27)
				)
				(justify mirror)
			)
		)
		(property "Value" ""
			(at 0 0 90)
			(layer "B.Fab")
			(effects
				(font
					(size 1.27 1.27)
				)
				(justify mirror)
			)
		)
		(duplicate_pad_numbers_are_jumpers no)
		(fp_line
			(start -1.524 0.762)
			(end 1.524 0.762)
			(stroke
				(width 0.1524)
				(type default)
			)
			(layer "B.SilkS")
		)
		(fp_line
			(start 1.524 0.762)
			(end 1.524 -0.762)
			(stroke
				(width 0.1524)
				(type default)
			)
			(layer "B.SilkS")
		)
		(fp_line
			(start -1.524 -0.762)
			(end -1.524 0.762)
			(stroke
				(width 0.1524)
				(type default)
			)
			(layer "B.SilkS")
		)
		(fp_line
			(start 1.524 -0.762)
			(end -1.524 -0.762)
			(stroke
				(width 0.1524)
				(type default)
			)
			(layer "B.SilkS")
		)
		(fp_line
			(start -1.1049 0.724916)
			(end -1.1049 -0.724916)
			(stroke
				(width 0.1)
				(type default)
			)
			(layer "B.Fab")
		)
		(fp_line
			(start 1.1049 0.724916)
			(end -1.1049 0.724916)
			(stroke
				(width 0.1)
				(type default)
			)
			(layer "B.Fab")
		)
		(fp_line
			(start -1.1049 -0.724916)
			(end 1.1049 -0.724916)
			(stroke
				(width 0.1)
				(type default)
			)
			(layer "B.Fab")
		)
		(fp_line
			(start 1.1049 -0.724916)
			(end 1.1049 0.724916)
			(stroke
				(width 0.1)
				(type default)
			)
			(layer "B.Fab")
		)
		(pad "1" smd rect
			(at 0.889 0 270)
			(size 1.016 1.27)
			(layers "B.Cu" "B.Mask" "B.Paste")
			(net "PVDDCR_CPU1_P0")
		)
		(pad "2" smd rect
			(at -0.889 0 270)
			(size 1.016 1.27)
			(layers "B.Cu" "B.Mask" "B.Paste")
			(net "GND")
		)
	)
	(footprint ""
		(layer "B.Cu")
		(at 175.075088 -244.085364)
		(property "Reference" "R507"
			(at 0 0 0)
			(layer "B.SilkS")
			(hide yes)
			(effects
				(font
					(size 1.27 1.27)
				)
				(justify mirror)
			)
		)
		(property "Value" ""
			(at 0 0 0)
			(layer "B.Fab")
			(effects
				(font
					(size 1.27 1.27)
				)
				(justify mirror)
			)
		)
		(duplicate_pad_numbers_are_jumpers no)
		(fp_line
			(start -0.7874 -0.4064)
			(end -0.7874 0.4064)
			(stroke
				(width 0.1524)
				(type default)
			)
			(layer "B.SilkS")
		)
		(fp_line
			(start -0.7874 0.4064)
			(end 0.7874 0.4064)
			(stroke
				(width 0.1524)
				(type default)
			)
			(layer "B.SilkS")
		)
		(fp_line
			(start 0.7874 -0.4064)
			(end -0.7874 -0.4064)
			(stroke
				(width 0.1524)
				(type default)
			)
			(layer "B.SilkS")
		)
		(fp_line
			(start 0.7874 0.4064)
			(end 0.7874 -0.4064)
			(stroke
				(width 0.1524)
				(type default)
			)
			(layer "B.SilkS")
		)
		(fp_line
			(start -0.67945 -0.3048)
			(end -0.67945 0.3048)
			(stroke
				(width 0.1)
				(type default)
			)
			(layer "B.Fab")
		)
		(fp_line
			(start -0.67945 0.3048)
			(end -0.120396 0.3048)
			(stroke
				(width 0.1)
				(type default)
			)
			(layer "B.Fab")
		)
		(fp_line
			(start -0.12065 -0.3048)
			(end -0.67945 -0.3048)
			(stroke
				(width 0.1)
				(type default)
			)
			(layer "B.Fab")
		)
		(fp_line
			(start -0.12065 -0.2794)
			(end -0.12065 -0.3048)
			(stroke
				(width 0.1)
				(type default)
			)
			(layer "B.Fab")
		)
		(fp_line
			(start -0.120396 0.2794)
			(end 0.12065 0.2794)
			(stroke
				(width 0.1)
				(type default)
			)
			(layer "B.Fab")
		)
		(fp_line
			(start -0.120396 0.3048)
			(end -0.120396 0.2794)
			(stroke
				(width 0.1)
				(type default)
			)
			(layer "B.Fab")
		)
		(fp_line
			(start 0.12065 -0.305054)
			(end 0.12065 -0.2794)
			(stroke
				(width 0.1)
				(type default)
			)
			(layer "B.Fab")
		)
		(fp_line
			(start 0.12065 -0.2794)
			(end -0.12065 -0.2794)
			(stroke
				(width 0.1)
				(type default)
			)
			(layer "B.Fab")
		)
		(fp_line
			(start 0.12065 0.2794)
			(end 0.12065 0.3048)
			(stroke
				(width 0.1)
				(type default)
			)
			(layer "B.Fab")
		)
		(fp_line
			(start 0.12065 0.3048)
			(end 0.67945 0.3048)
			(stroke
				(width 0.1)
				(type default)
			)
			(layer "B.Fab")
		)
		(fp_line
			(start 0.67945 -0.305054)
			(end 0.12065 -0.305054)
			(stroke
				(width 0.1)
				(type default)
			)
			(layer "B.Fab")
		)
		(fp_line
			(start 0.67945 0.3048)
			(end 0.67945 -0.305054)
			(stroke
				(width 0.1)
				(type default)
			)
			(layer "B.Fab")
		)
		(pad "1" smd circle
			(at 0.40005 0 180)
			(size 0 0)
			(layers "B.Cu" "B.Mask" "B.Paste")
			(net "M_H_CPU1_ALERT_N")
		)
		(pad "2" smd circle
			(at -0.40005 0 180)
			(size 0 0)
			(layers "B.Cu" "B.Mask" "B.Paste")
			(net "M_H_CPU1_ALERT_R_N")
		)
	)
)
